# T6G (Grand Teton) — schematic netlist excerpt (pin names and nets, part order shuffled) for the footprints in the layout excerpt that follows; sources: Cadence DE-HDL packaged netlist, KiCad conversion of 04192023_DAF0TMB3IC0_F0TG_MB_C_brd_V02_OCP.brd

C683  Q_CAP_DIFFBUS  DIFF BUS_0.22UF 6.3V 20% X6S  pkg C0201  page 67 : \1\ = P5E_CPU1_G1_TX_C_DP<13> ; \2\ = P5E_CPU1_G1_TX_DP<13>
R4532  Q_RES  10K 1% CHIP  pkg 0402LF  page 135 : A = P3V3_AUX ; B = HP_LVC3_OCP_V3_1_P12V_PWRGD
R1203  Q_RES  33 5% CHIP  pkg 0402LF  page 81 : A = BIOS_DEBUG_MODE_R ; B = BIOS_DEBUG_MODE

(kicad_pcb
	(version 20260206)
	(generator "pcbnew")
	(generator_version "10.0")
	(general
		(thickness 1.6)
		(legacy_teardrops no)
	)
	(paper "A4")
	(title_block
		(title "04192023_DAF0TMB3IC0_F0TG_MB_C_brd_V02_OCP.brd")
		(comment 1 "Grand Teton / footprints 1435-1437 of 8354")
	)
	(layers
		(0 "F.Cu" signal "TOP")
		(4 "In1.Cu" signal "GND")
		(6 "In2.Cu" signal "IN1")
		(8 "In3.Cu" signal "GND1")
		(10 "In4.Cu" signal "IN2")
		(12 "In5.Cu" signal "GND2")
		(14 "In6.Cu" signal "IN3")
		(16 "In7.Cu" signal "GND3")
		(18 "In8.Cu" signal "VCC")
		(20 "In9.Cu" signal "VCC1")
		(22 "In10.Cu" signal "GND4")
		(24 "In11.Cu" signal "IN4")
		(26 "In12.Cu" signal "GND5")
		(28 "In13.Cu" signal "IN5")
		(30 "In14.Cu" signal "GND6")
		(32 "In15.Cu" signal "IN6")
		(34 "In16.Cu" signal "GND7")
		(2 "B.Cu" signal "BOTTOM")
		(9 "F.Adhes" user "F.Adhesive")
		(11 "B.Adhes" user "B.Adhesive")
		(13 "F.Paste" user "Package Geometry/Pastemask Top")
		(15 "B.Paste" user "Package Geometry/Pastemask Bottom")
		(5 "F.SilkS" user "Ref Des/Silkscreen Top")
		(7 "B.SilkS" user "Ref Des/Silkscreen Bottom")
		(1 "F.Mask" user "Board Geometry/Soldermask Top")
		(3 "B.Mask" user "Board Geometry/Soldermask Bottom")
		(17 "Dwgs.User" user "User.Drawings")
		(19 "Cmts.User" user "User.Comments")
		(21 "Eco1.User" user "User.Eco1")
		(23 "Eco2.User" user "User.Eco2")
		(25 "Edge.Cuts" user "Board Geometry/Outline")
		(27 "Margin" user)
		(31 "F.CrtYd" user "Package Geometry/Place Bound Top")
		(29 "B.CrtYd" user "Package Geometry/Place Bound Bottom")
		(35 "F.Fab" user "Ref Des/Assembly Top")
		(33 "B.Fab" user "Ref Des/Assembly Bottom")
	)
	(footprint ""
		(layer "F.Cu")
		(at 187.071 -129.377948 90)
		(property "Reference" "R1203"
			(at 0 0 90)
			(layer "F.SilkS")
			(hide yes)
			(effects
				(font
					(size 1.27 1.27)
				)
			)
		)
		(property "Value" ""
			(at 0 0 90)
			(layer "F.Fab")
			(effects
				(font
					(size 1.27 1.27)
				)
			)
		)
		(duplicate_pad_numbers_are_jumpers no)
		(fp_line
			(start 0.7874 -0.4064)
			(end 0.7874 0.4064)
			(stroke
				(width 0.1524)
				(type default)
			)
			(layer "F.SilkS")
		)
		(fp_line
			(start -0.7874 -0.4064)
			(end 0.7874 -0.4064)
			(stroke
				(width 0.1524)
				(type default)
			)
			(layer "F.SilkS")
		)
		(fp_line
			(start 0.7874 0.4064)
			(end -0.7874 0.4064)
			(stroke
				(width 0.1524)
				(type default)
			)
			(layer "F.SilkS")
		)
		(fp_line
			(start -0.7874 0.4064)
			(end -0.7874 -0.4064)
			(stroke
				(width 0.1524)
				(type default)
			)
			(layer "F.SilkS")
		)
		(fp_line
			(start -0.12065 -0.305054)
			(end -0.12065 -0.2794)
			(stroke
				(width 0.1)
				(type default)
			)
			(layer "F.Fab")
		)
		(fp_line
			(start -0.67945 -0.305054)
			(end -0.12065 -0.305054)
			(stroke
				(width 0.1)
				(type default)
			)
			(layer "F.Fab")
		)
		(fp_line
			(start 0.67945 -0.3048)
			(end 0.67945 0.3048)
			(stroke
				(width 0.1)
				(type default)
			)
			(layer "F.Fab")
		)
		(fp_line
			(start 0.12065 -0.3048)
			(end 0.67945 -0.3048)
			(stroke
				(width 0.1)
				(type default)
			)
			(layer "F.Fab")
		)
		(fp_line
			(start 0.12065 -0.2794)
			(end 0.12065 -0.3048)
			(stroke
				(width 0.1)
				(type default)
			)
			(layer "F.Fab")
		)
		(fp_line
			(start -0.12065 -0.2794)
			(end 0.12065 -0.2794)
			(stroke
				(width 0.1)
				(type default)
			)
			(layer "F.Fab")
		)
		(fp_line
			(start 0.120396 0.2794)
			(end -0.12065 0.2794)
			(stroke
				(width 0.1)
				(type default)
			)
			(layer "F.Fab")
		)
		(fp_line
			(start -0.12065 0.2794)
			(end -0.12065 0.3048)
			(stroke
				(width 0.1)
				(type default)
			)
			(layer "F.Fab")
		)
		(fp_line
			(start 0.67945 0.3048)
			(end 0.120396 0.3048)
			(stroke
				(width 0.1)
				(type default)
			)
			(layer "F.Fab")
		)
		(fp_line
			(start 0.120396 0.3048)
			(end 0.120396 0.2794)
			(stroke
				(width 0.1)
				(type default)
			)
			(layer "F.Fab")
		)
		(fp_line
			(start -0.12065 0.3048)
			(end -0.67945 0.3048)
			(stroke
				(width 0.1)
				(type default)
			)
			(layer "F.Fab")
		)
		(fp_line
			(start -0.67945 0.3048)
			(end -0.67945 -0.305054)
			(stroke
				(width 0.1)
				(type default)
			)
			(layer "F.Fab")
		)
		(pad "1" smd circle
			(at -0.40005 0 90)
			(size 0 0)
			(layers "F.Cu" "F.Mask" "F.Paste")
			(net "BIOS_DEBUG_MODE_R")
		)
		(pad "2" smd circle
			(at 0.40005 0 90)
			(size 0 0)
			(layers "F.Cu" "F.Mask" "F.Paste")
			(net "BIOS_DEBUG_MODE")
		)
	)
	(footprint ""
		(layer "F.Cu")
		(at 22.010878 -16.099536 90)
		(property "Reference" "C683"
			(at 0 0 90)
			(layer "F.SilkS")
			(hide yes)
			(effects
				(font
					(size 1.27 1.27)
				)
			)
		)
		(property "Value" ""
			(at 0 0 90)
			(layer "F.Fab")
			(effects
				(font
					(size 1.27 1.27)
				)
			)
		)
		(duplicate_pad_numbers_are_jumpers no)
		(fp_line
			(start 0.299974 -0.150114)
			(end 0.299974 0.150114)
			(stroke
				(width 0.1)
				(type default)
			)
			(layer "F.Fab")
		)
		(fp_line
			(start -0.299974 -0.150114)
			(end 0.299974 -0.150114)
			(stroke
				(width 0.1)
				(type default)
			)
			(layer "F.Fab")
		)
		(fp_line
			(start 0.299974 0.150114)
			(end -0.299974 0.150114)
			(stroke
				(width 0.1)
				(type default)
			)
			(layer "F.Fab")
		)
		(fp_line
			(start -0.299974 0.150114)
			(end -0.299974 -0.150114)
			(stroke
				(width 0.1)
				(type default)
			)
			(layer "F.Fab")
		)
		(pad "1" smd rect
			(at -0.2667 0 90)
			(size 0.3048 0.381)
			(layers "F.Cu" "F.Mask" "F.Paste")
			(net "P5E_CPU1_G1_TX_C_DP<13>")
		)
		(pad "2" smd rect
			(at 0.2667 0 90)
			(size 0.3048 0.381)
			(layers "F.Cu" "F.Mask" "F.Paste")
			(net "P5E_CPU1_G1_TX_DP<13>")
		)
	)
	(footprint ""
		(layer "F.Cu")
		(at 437.875172 -28.668218)
		(property "Reference" "R4532"
			(at 0 0 0)
			(layer "F.SilkS")
			(hide yes)
			(effects
				(font
					(size 1.27 1.27)
				)
			)
		)
		(property "Value" ""
			(at 0 0 0)
			(layer "F.Fab")
			(effects
				(font
					(size 1.27 1.27)
				)
			)
		)
		(duplicate_pad_numbers_are_jumpers no)
		(fp_line
			(start -0.7874 -0.4064)
			(end 0.7874 -0.4064)
			(stroke
				(width 0.1524)
				(type default)
			)
			(layer "F.SilkS")
		)
		(fp_line
			(start -0.7874 0.4064)
			(end -0.7874 -0.4064)
			(stroke
				(width 0.1524)
				(type default)
			)
			(layer "F.SilkS")
		)
		(fp_line
			(start 0.7874 -0.4064)
			(end 0.7874 0.4064)
			(stroke
				(width 0.1524)
				(type default)
			)
			(layer "F.SilkS")
		)
		(fp_line
			(start 0.7874 0.4064)
			(end -0.7874 0.4064)
			(stroke
				(width 0.1524)
				(type default)
			)
			(layer "F.SilkS")
		)
		(fp_line
			(start -0.67945 -0.305054)
			(end -0.12065 -0.305054)
			(stroke
				(width 0.1)
				(type default)
			)
			(layer "F.Fab")
		)
		(fp_line
			(start -0.67945 0.3048)
			(end -0.67945 -0.305054)
			(stroke
				(width 0.1)
				(type default)
			)
			(layer "F.Fab")
		)
		(fp_line
			(start -0.12065 -0.305054)
			(end -0.12065 -0.2794)
			(stroke
				(width 0.1)
				(type default)
			)
			(layer "F.Fab")
		)
		(fp_line
			(start -0.12065 -0.2794)
			(end 0.12065 -0.2794)
			(stroke
				(width 0.1)
				(type default)
			)
			(layer "F.Fab")
		)
		(fp_line
			(start -0.12065 0.2794)
			(end -0.12065 0.3048)
			(stroke
				(width 0.1)
				(type default)
			)
			(layer "F.Fab")
		)
		(fp_line
			(start -0.12065 0.3048)
			(end -0.67945 0.3048)
			(stroke
				(width 0.1)
				(type default)
			)
			(layer "F.Fab")
		)
		(fp_line
			(start 0.120396 0.2794)
			(end -0.12065 0.2794)
			(stroke
				(width 0.1)
				(type default)
			)
			(layer "F.Fab")
		)
		(fp_line
			(start 0.120396 0.3048)
			(end 0.120396 0.2794)
			(stroke
				(width 0.1)
				(type default)
			)
			(layer "F.Fab")
		)
		(fp_line
			(start 0.12065 -0.3048)
			(end 0.67945 -0.3048)
			(stroke
				(width 0.1)
				(type default)
			)
			(layer "F.Fab")
		)
		(fp_line
			(start 0.12065 -0.2794)
			(end 0.12065 -0.3048)
			(stroke
				(width 0.1)
				(type default)
			)
			(layer "F.Fab")
		)
		(fp_line
			(start 0.67945 -0.3048)
			(end 0.67945 0.3048)
			(stroke
				(width 0.1)
				(type default)
			)
			(layer "F.Fab")
		)
		(fp_line
			(start 0.67945 0.3048)
			(end 0.120396 0.3048)
			(stroke
				(width 0.1)
				(type default)
			)
			(layer "F.Fab")
		)
		(pad "1" smd circle
			(at -0.40005 0)
			(size 0 0)
			(layers "F.Cu" "F.Mask" "F.Paste")
			(net "P3V3_AUX")
		)
		(pad "2" smd circle
			(at 0.40005 0)
			(size 0 0)
			(layers "F.Cu" "F.Mask" "F.Paste")
			(net "HP_LVC3_OCP_V3_1_P12V_PWRGD")
		)
	)
)
